# S9S_MB_2U (Grand Teton) — schematic netlist excerpt (pin names and nets, part order shuffled) for the footprints in the layout excerpt that follows; sources: Cadence DE-HDL packaged netlist, KiCad conversion of 03242023_DA0F0TMBIJ0_F0T_Motherboard_J_brd_V01_OCP.brd

J28  SCONN288_ADR50017P087CC  SCONN288_ADR50017-P087CC IO  pkg DDR288S_1-1VXB  page 109
  VIN_BULK0  = P12V_S3_AUX_CPU1_NVDIMM
  RFU0  = TP_CHF_CPU1_DIMM2_FRU_0
  VIN_MGMT  = P3V3_AUX
  HSCL  = I3C_SPD_DDREFGH_CPU1_LVC1_SCL_3
  HSDA  = I3C_SPD_DDREFGH_CPU1_LVC1_SDA
  VSS0  = GND
  DQ0_A  = M_F_CPU1_SA_DQ<0>
  VSS1  = GND
  DQ1_A  = M_F_CPU1_SA_DQ<1>
  VSS2  = GND
  DQS0_A_T  = M_F_CPU1_SA_DQS_DP<0>
  DQS0_A_C  = M_F_CPU1_SA_DQS_DN<0>
  VSS3  = GND
  DQ4_A  = M_F_CPU1_SA_DQ<4>
  VSS4  = GND
  DQ5_A  = M_F_CPU1_SA_DQ<5>
  VSS5  = GND
  DQ8_A  = M_F_CPU1_SA_DQ<8>
  VSS6  = GND
  DQ9_A  = M_F_CPU1_SA_DQ<9>
  VSS7  = GND
  DQS1_A_T  = M_F_CPU1_SA_DQS_DP<1>
  DQS1_A_C  = M_F_CPU1_SA_DQS_DN<1>
  VSS8  = GND
  DQ12_A  = M_F_CPU1_SA_DQ<12>
  VSS9  = GND
  DQ13_A  = M_F_CPU1_SA_DQ<13>
  VSS10  = GND
  DQ16_A  = M_F_CPU1_SA_DQ<16>
  VSS11  = GND
  DQ17_A  = M_F_CPU1_SA_DQ<17>
  VSS12  = GND
  DQS2_A_T  = M_F_CPU1_SA_DQS_DP<2>
  DQS2_A_C  = M_F_CPU1_SA_DQS_DN<2>
  VSS13  = GND
  DQ20_A  = M_F_CPU1_SA_DQ<20>
  VSS14  = GND
  DQ21_A  = M_F_CPU1_SA_DQ<21>
  VSS15  = GND
  DQ24_A  = M_F_CPU1_SA_DQ<24>
  VSS16  = GND
  DQ25_A  = M_F_CPU1_SA_DQ<25>
  VSS17  = GND
  DQS3_A_T  = M_F_CPU1_SA_DQS_DP<3>
  DQS3_A_C  = M_F_CPU1_SA_DQS_DN<3>
  VSS18  = GND
  DQ28_A  = M_F_CPU1_SA_DQ<28>
  VSS19  = GND
  DQ29_A  = M_F_CPU1_SA_DQ<29>
  VSS20  = GND
  CB0_A  = M_F_CPU1_SA_CB<0>
  VSS21  = GND
  CB1_A  = M_F_CPU1_SA_CB<1>
  VSS22  = GND
  DQS4_A_T  = M_F_CPU1_SA_DQS_DP<4>
  DQS4_A_C  = M_F_CPU1_SA_DQS_DN<4>
  VSS23  = GND
  CB4_A  = M_F_CPU1_SA_CB<4>
  VSS24  = GND
  CB5_A  = M_F_CPU1_SA_CB<5>
  VSS25  = GND
  ALERT_N  = M_F_CPU1_ALERT_N
  VSS26  = GND
  CS0_A_N  = M_F_CPU1_SA_CS_N<2>
  VSS27  = GND
  CA0_A  = M_F_CPU1_SA_CA<0>
  VSS28  = GND
  CA2_A  = M_F_CPU1_SA_CA<2>
  VSS29  = GND
  CA4_A  = M_F_CPU1_SA_CA<4>
  VSS30  = GND
  CA6_A  = M_F_CPU1_SA_CA<6>
  VSS31  = GND
  PAR_A  = M_F_CPU1_SA_PAR
  VSS32  = GND
  CA0_B  = M_F_CPU1_SB_CA<0>
  VSS33  = GND
  CA2_B  = M_F_CPU1_SB_CA<2>
  VSS34  = GND
  CA4_B  = M_F_CPU1_SB_CA<4>
  VSS35  = GND
  CA6_B  = M_F_CPU1_SB_CA<6>
  VSS36  = GND
  CS0_B_N  = M_F_CPU1_SB_CS_N<2>
  VSS37  = GND
  \lbd||rsp_a_n\  = M_F_CPU1_SA_RSP<1>
  \lbs||rsp_b_n\  = M_F_CPU1_SB_RSP<1>
  VSS38  = GND
  CB4_B  = M_F_CPU1_SB_CB<4>
  VSS39  = GND
  CB5_B  = M_F_CPU1_SB_CB<5>
  VSS40  = GND
  \dqs9_b_t||tdqs9_b_t||dbi4_b_n\  = M_F_CPU1_SB_DQS_DP<9>
  \dqs9_b_c||tdqs9_b_c\  = M_F_CPU1_SB_DQS_DN<9>
  VSS41  = GND
  CB0_B  = M_F_CPU1_SB_CB<0>
  VSS42  = GND
  CB1_B  = M_F_CPU1_SB_CB<1>
  VSS43  = GND
  DQ0_B  = M_F_CPU1_SB_DQ<0>
  VSS44  = GND
  DQ1_B  = M_F_CPU1_SB_DQ<1>
  VSS45  = GND
  DQS0_B_T  = M_F_CPU1_SB_DQS_DP<0>
  DQS0_B_C  = M_F_CPU1_SB_DQS_DN<0>
  VSS46  = GND
  DQ4_B  = M_F_CPU1_SB_DQ<4>
  VSS47  = GND
  DQ5_B  = M_F_CPU1_SB_DQ<5>
  VSS48  = GND
  DQ8_B  = M_F_CPU1_SB_DQ<8>
  VSS49  = GND
  DQ9_B  = M_F_CPU1_SB_DQ<9>
  VSS50  = GND
  DQS1_B_T  = M_F_CPU1_SB_DQS_DP<1>
  DQS1_B_C  = M_F_CPU1_SB_DQS_DN<1>
  VSS51  = GND
  DQ12_B  = M_F_CPU1_SB_DQ<12>
  VSS52  = GND
  DQ13_B  = M_F_CPU1_SB_DQ<13>
  VSS53  = GND
  DQ16_B  = M_F_CPU1_SB_DQ<16>
  VSS54  = GND
  DQ17_B  = M_F_CPU1_SB_DQ<17>
  VSS55  = GND
  DQS2_B_T  = M_F_CPU1_SB_DQS_DP<2>
  DQS2_B_C  = M_F_CPU1_SB_DQS_DN<2>
  VSS56  = GND
  DQ20_B  = M_F_CPU1_SB_DQ<20>
  VSS57  = GND
  DQ21_B  = M_F_CPU1_SB_DQ<21>
  VSS58  = GND
  DQ24_B  = M_F_CPU1_SB_DQ<24>
  VSS59  = GND
  DQ25_B  = M_F_CPU1_SB_DQ<25>
  VSS60  = GND
  DQS3_B_T  = M_F_CPU1_SB_DQS_DP<3>
  DQS3_B_C  = M_F_CPU1_SB_DQS_DN<3>
  VSS61  = GND
  DQ28_B  = M_F_CPU1_SB_DQ<28>
  VSS62  = GND
  DQ29_B  = M_F_CPU1_SB_DQ<29>
  VSS63  = GND
  RFU1  = TP_CHF_CPU1_DIMM2_FRU_1
  VIN_BULK1  = P12V_S3_AUX_CPU1_NVDIMM
  VIN_BULK2  = P12V_S3_AUX_CPU1_NVDIMM
  \pwr_good||fail_n\  = PWRGD_CHF_CPU1_DIMM2
  HSA  = PD_CHF_CPU1_DIMM2_SAA
  RFU2  = TP_CHF_CPU1_DIMM2_FRU_2
  RFU3  = TP_CHF_CPU1_DIMM2_FRU_3
  VSS64  = GND
  DQ2_A  = M_F_CPU1_SA_DQ<2>
  VSS65  = GND
  DQ3_A  = M_F_CPU1_SA_DQ<3>
  VSS66  = GND
  \dqs5_a_c||tdqs5_a_c||dqs5_a_t||tdqs5_a_t\  = M_F_CPU1_SA_DQS_DN<5>
  \dqs5_a_t||tdqs5_a_t\  = M_F_CPU1_SA_DQS_DP<5>
  VSS67  = GND
  DQ6_A  = M_F_CPU1_SA_DQ<6>
  VSS68  = GND
  DQ7_A  = M_F_CPU1_SA_DQ<7>
  VSS69  = GND
  DQ10_A  = M_F_CPU1_SA_DQ<10>
  VSS70  = GND
  DQ11_A  = M_F_CPU1_SA_DQ<11>
  VSS71  = GND
  \dqs6_a_c||tdqs6_a_c||dqs6_a_t||tdqs6_a_t\  = M_F_CPU1_SA_DQS_DN<6>
  \dqs6_a_t||tdqs6_a_t\  = M_F_CPU1_SA_DQS_DP<6>
  VSS72  = GND
  DQ14_A  = M_F_CPU1_SA_DQ<14>
  VSS73  = GND
  DQ15_A  = M_F_CPU1_SA_DQ<15>
  VSS74  = GND
  DQ18_A  = M_F_CPU1_SA_DQ<18>
  VSS75  = GND
  DQ19_A  = M_F_CPU1_SA_DQ<19>
  VSS76  = GND
  \dqs7_a_c||tdqs7_a_c\  = M_F_CPU1_SA_DQS_DN<7>
  \dqs7_a_t||tdqs7_a_t\  = M_F_CPU1_SA_DQS_DP<7>
  VSS77  = GND
  DQ22_A  = M_F_CPU1_SA_DQ<22>
  VSS78  = GND
  DQ23_A  = M_F_CPU1_SA_DQ<23>
  VSS79  = GND
  DQ26_A  = M_F_CPU1_SA_DQ<26>
  VSS80  = GND
  DQ27_A  = M_F_CPU1_SA_DQ<27>
  VSS81  = GND
  \dqs8_a_c||tdqs8_a_c\  = M_F_CPU1_SA_DQS_DN<8>
  \dqs8_a_t||tdqs8_a_t\  = M_F_CPU1_SA_DQS_DP<8>
  VSS82  = GND
  DQ30_A  = M_F_CPU1_SA_DQ<30>
  VSS83  = GND
  DQ31_A  = M_F_CPU1_SA_DQ<31>
  VSS84  = GND
  CB2_A  = M_F_CPU1_SA_CB<2>
  VSS85  = GND
  CB3_A  = M_F_CPU1_SA_CB<3>
  VSS86  = GND
  \dqs9_a_c||tdqs9_a_c\  = M_F_CPU1_SA_DQS_DN<9>
  \dqs9_a_t||tdqs9_a_t\  = M_F_CPU1_SA_DQS_DP<9>
  VSS87  = GND
  CB6_A  = M_F_CPU1_SA_CB<6>
  VSS88  = GND
  CB7_A  = M_F_CPU1_SA_CB<7>
  VSS89  = GND
  RESET_N  = RST_M_EF_CPU1_FPGA_N
  VSS90  = GND
  CS1_A_N  = M_F_CPU1_SA_CS_N<3>
  VSS91  = GND
  CA1_A  = M_F_CPU1_SA_CA<1>
  VSS92  = GND
  CA3_A  = M_F_CPU1_SA_CA<3>
  VSS93  = GND
  CA5_A  = M_F_CPU1_SA_CA<5>
  VSS94  = GND
  CK_T  = M_F_CPU1_CLK_DP<1>
  CK_C  = M_F_CPU1_CLK_DN<1>
  VSS95  = GND
  RFU4  = TP_CHF_CPU1_DIMM2_FRU_4
  CA1_B  = M_F_CPU1_SB_CA<1>
  VSS96  = GND
  CA3_B  = M_F_CPU1_SB_CA<3>
  VSS97  = GND
  CA5_B  = M_F_CPU1_SB_CA<5>
  VSS98  = GND
  PAR_B  = M_F_CPU1_SB_PAR
  VSS99  = GND
  CS1_B_N  = M_F_CPU1_SB_CS_N<3>
  VSS100  = GND
  RFU5  = TP_CHF_CPU1_DIMM2_FRU_5
  RFU6  = TP_CHF_CPU1_DIMM2_FRU_6
  VSS101  = GND
  CB6_B  = M_F_CPU1_SB_CB<6>
  VSS102  = GND
  CB7_B  = M_F_CPU1_SB_CB<7>
  VSS103  = GND
  DQS4_B_C  = M_F_CPU1_SB_DQS_DN<4>
  DQS4_B_T  = M_F_CPU1_SB_DQS_DP<4>
  VSS104  = GND
  CB2_B  = M_F_CPU1_SB_CB<2>
  VSS105  = GND
  CB3_B  = M_F_CPU1_SB_CB<3>
  VSS106  = GND
  DQ2_B  = M_F_CPU1_SB_DQ<2>
  VSS107  = GND
  DQ3_B  = M_F_CPU1_SB_DQ<3>
  VSS108  = GND
  \dqs5_b_c||tdqs5_b_c\  = M_F_CPU1_SB_DQS_DN<5>
  \dqs5_b_t||tdqs5_b_t\  = M_F_CPU1_SB_DQS_DP<5>
  VSS109  = GND
  DQ6_B  = M_F_CPU1_SB_DQ<6>
  VSS110  = GND
  DQ7_B  = M_F_CPU1_SB_DQ<7>
  VSS111  = GND
  DQ10_B  = M_F_CPU1_SB_DQ<10>
  VSS112  = GND
  DQ11_B  = M_F_CPU1_SB_DQ<11>
  VSS113  = GND
  \dqs6_b_c||tdqs6_b_c\  = M_F_CPU1_SB_DQS_DN<6>
  \dqs6_b_t||tdqs6_b_t\  = M_F_CPU1_SB_DQS_DP<6>
  VSS114  = GND
  DQ14_B  = M_F_CPU1_SB_DQ<14>
  VSS115  = GND
  DQ15_B  = M_F_CPU1_SB_DQ<15>
  VSS116  = GND
  DQ18_B  = M_F_CPU1_SB_DQ<18>
  VSS117  = GND
  DQ19_B  = M_F_CPU1_SB_DQ<19>
  VSS118  = GND
  \dqs7_b_c||tdqs7_b_c\  = M_F_CPU1_SB_DQS_DN<7>
  \dqs7_b_t||tdqs7_b_t\  = M_F_CPU1_SB_DQS_DP<7>
  VSS119  = GND
  DQ22_B  = M_F_CPU1_SB_DQ<22>
  VSS120  = GND
  DQ23_B  = M_F_CPU1_SB_DQ<23>
  VSS121  = GND
  DQ26_B  = M_F_CPU1_SB_DQ<26>
  VSS122  = GND
  DQ27_B  = M_F_CPU1_SB_DQ<27>
  VSS123  = GND
  \dqs8_b_c||tdqs8_b_c\  = M_F_CPU1_SB_DQS_DN<8>
  \dqs8_b_t||tdqs8_b_t\  = M_F_CPU1_SB_DQS_DP<8>
  VSS124  = GND
  DQ30_B  = M_F_CPU1_SB_DQ<30>
  VSS125  = GND
  DQ31_B  = M_F_CPU1_SB_DQ<31>
  VSS126  = GND
  G1  = GND
  G2  = GND
  G3  = GND

(kicad_pcb
	(version 20260206)
	(generator "pcbnew")
	(generator_version "10.0")
	(general
		(thickness 1.6)
		(legacy_teardrops no)
	)
	(paper "A4")
	(title_block
		(title "03242023_DA0F0TMBIJ0_F0T_Motherboard_J_brd_V01_OCP.brd")
		(comment 1 "Grand Teton / footprint 3431 of 6105 (J28), pads 138-182 of 291")
	)
	(layers
		(0 "F.Cu" signal "TOP")
		(4 "In1.Cu" signal "GND")
		(6 "In2.Cu" signal "IN1")
		(8 "In3.Cu" signal "GND1")
		(10 "In4.Cu" signal "IN2")
		(12 "In5.Cu" signal "GND2")
		(14 "In6.Cu" signal "IN3")
		(16 "In7.Cu" signal "GND3")
		(18 "In8.Cu" signal "VCC")
		(20 "In9.Cu" signal "VCC1")
		(22 "In10.Cu" signal "GND4")
		(24 "In11.Cu" signal "IN4")
		(26 "In12.Cu" signal "GND5")
		(28 "In13.Cu" signal "IN5")
		(30 "In14.Cu" signal "GND6")
		(32 "In15.Cu" signal "IN6")
		(34 "In16.Cu" signal "GND7")
		(2 "B.Cu" signal "BOTTOM")
		(9 "F.Adhes" user "F.Adhesive")
		(11 "B.Adhes" user "B.Adhesive")
		(13 "F.Paste" user "Package Geometry/Pastemask Top")
		(15 "B.Paste" user "Package Geometry/Pastemask Bottom")
		(5 "F.SilkS" user "Ref Des/Silkscreen Top")
		(7 "B.SilkS" user "Ref Des/Silkscreen Bottom")
		(1 "F.Mask" user "Board Geometry/Soldermask Top")
		(3 "B.Mask" user "Board Geometry/Soldermask Bottom")
		(17 "Dwgs.User" user "User.Drawings")
		(19 "Cmts.User" user "User.Comments")
		(21 "Eco1.User" user "User.Eco1")
		(23 "Eco2.User" user "User.Eco2")
		(25 "Edge.Cuts" user "Board Geometry/Outline")
		(27 "Margin" user)
		(31 "F.CrtYd" user "Package Geometry/Place Bound Top")
		(29 "B.CrtYd" user "Package Geometry/Place Bound Bottom")
		(35 "F.Fab" user "Ref Des/Assembly Top")
		(33 "B.Fab" user "Ref Des/Assembly Bottom")
	)
	(footprint ""
		(layer "F.Cu")
		(at 175.95088 -258.091686)
		(property "Reference" "J28"
			(at -0.26924 -81.680812 0)
			(unlocked yes)
			(layer "F.SilkS")
			(effects
				(font
					(size 0.7874 0.5842)
					(thickness 0.1524)
				)
				(justify left)
			)
		)
		(property "Value" ""
			(at 0 0 0)
			(layer "F.Fab")
			(effects
				(font
					(size 1.27 1.27)
				)
			)
		)
		(duplicate_pad_numbers_are_jumpers no)
		(pad "138" smd rect
			(at -2.050034 58.224928 270)
			(size 0.519938 1.4986)
			(layers "F.Cu" "F.Mask" "F.Paste")
			(net "M_F_CPU1_SB_DQS_DN<3>")
		)
		(pad "139" smd rect
			(at -2.050034 59.075066 270)
			(size 0.519938 1.4986)
			(layers "F.Cu" "F.Mask" "F.Paste")
			(net "GND")
		)
		(pad "140" smd rect
			(at -2.050034 59.92495 270)
			(size 0.519938 1.4986)
			(layers "F.Cu" "F.Mask" "F.Paste")
			(net "M_F_CPU1_SB_DQ<28>")
		)
		(pad "141" smd rect
			(at -2.050034 60.775088 270)
			(size 0.519938 1.4986)
			(layers "F.Cu" "F.Mask" "F.Paste")
			(net "GND")
		)
		(pad "142" smd rect
			(at -2.050034 61.624972 270)
			(size 0.519938 1.4986)
			(layers "F.Cu" "F.Mask" "F.Paste")
			(net "M_F_CPU1_SB_DQ<29>")
		)
		(pad "143" smd rect
			(at -2.050034 62.47511 270)
			(size 0.519938 1.4986)
			(layers "F.Cu" "F.Mask" "F.Paste")
			(net "GND")
		)
		(pad "144" smd rect
			(at -2.050034 63.324994 270)
			(size 0.519938 1.4986)
			(layers "F.Cu" "F.Mask" "F.Paste")
			(net "TP_CHF_CPU1_DIMM2_FRU_1")
		)
		(pad "145" smd rect
			(at 2.050034 -63.324994 270)
			(size 0.519938 1.4986)
			(layers "F.Cu" "F.Mask" "F.Paste")
			(net "P12V_S3_AUX_CPU1_NVDIMM")
		)
		(pad "146" smd rect
			(at 2.050034 -62.47511 270)
			(size 0.519938 1.4986)
			(layers "F.Cu" "F.Mask" "F.Paste")
			(net "P12V_S3_AUX_CPU1_NVDIMM")
		)
		(pad "147" smd rect
			(at 2.050034 -61.624972 270)
			(size 0.519938 1.4986)
			(layers "F.Cu" "F.Mask" "F.Paste")
			(net "PWRGD_CHF_CPU1_DIMM2")
		)
		(pad "148" smd rect
			(at 2.050034 -60.775088 270)
			(size 0.519938 1.4986)
			(layers "F.Cu" "F.Mask" "F.Paste")
			(net "PD_CHF_CPU1_DIMM2_SAA")
		)
		(pad "149" smd rect
			(at 2.050034 -59.92495 270)
			(size 0.519938 1.4986)
			(layers "F.Cu" "F.Mask" "F.Paste")
			(net "TP_CHF_CPU1_DIMM2_FRU_2")
		)
		(pad "150" smd rect
			(at 2.050034 -59.075066 270)
			(size 0.519938 1.4986)
			(layers "F.Cu" "F.Mask" "F.Paste")
			(net "TP_CHF_CPU1_DIMM2_FRU_3")
		)
		(pad "151" smd rect
			(at 2.050034 -58.224928 270)
			(size 0.519938 1.4986)
			(layers "F.Cu" "F.Mask" "F.Paste")
			(net "GND")
		)
		(pad "152" smd rect
			(at 2.050034 -57.375044 270)
			(size 0.519938 1.4986)
			(layers "F.Cu" "F.Mask" "F.Paste")
			(net "M_F_CPU1_SA_DQ<2>")
		)
		(pad "153" smd rect
			(at 2.050034 -56.524906 270)
			(size 0.519938 1.4986)
			(layers "F.Cu" "F.Mask" "F.Paste")
			(net "GND")
		)
		(pad "154" smd rect
			(at 2.050034 -55.675022 270)
			(size 0.519938 1.4986)
			(layers "F.Cu" "F.Mask" "F.Paste")
			(net "M_F_CPU1_SA_DQ<3>")
		)
		(pad "155" smd rect
			(at 2.050034 -54.824884 270)
			(size 0.519938 1.4986)
			(layers "F.Cu" "F.Mask" "F.Paste")
			(net "GND")
		)
		(pad "156" smd rect
			(at 2.050034 -53.975 270)
			(size 0.519938 1.4986)
			(layers "F.Cu" "F.Mask" "F.Paste")
			(net "M_F_CPU1_SA_DQS_DN<5>")
		)
		(pad "157" smd rect
			(at 2.050034 -53.125116 270)
			(size 0.519938 1.4986)
			(layers "F.Cu" "F.Mask" "F.Paste")
			(net "M_F_CPU1_SA_DQS_DP<5>")
		)
		(pad "158" smd rect
			(at 2.050034 -52.274978 270)
			(size 0.519938 1.4986)
			(layers "F.Cu" "F.Mask" "F.Paste")
			(net "GND")
		)
		(pad "159" smd rect
			(at 2.050034 -51.425094 270)
			(size 0.519938 1.4986)
			(layers "F.Cu" "F.Mask" "F.Paste")
			(net "M_F_CPU1_SA_DQ<6>")
		)
		(pad "160" smd rect
			(at 2.050034 -50.574956 270)
			(size 0.519938 1.4986)
			(layers "F.Cu" "F.Mask" "F.Paste")
			(net "GND")
		)
		(pad "161" smd rect
			(at 2.050034 -49.725072 270)
			(size 0.519938 1.4986)
			(layers "F.Cu" "F.Mask" "F.Paste")
			(net "M_F_CPU1_SA_DQ<7>")
		)
		(pad "162" smd rect
			(at 2.050034 -48.874934 270)
			(size 0.519938 1.4986)
			(layers "F.Cu" "F.Mask" "F.Paste")
			(net "GND")
		)
		(pad "163" smd rect
			(at 2.050034 -48.02505 270)
			(size 0.519938 1.4986)
			(layers "F.Cu" "F.Mask" "F.Paste")
			(net "M_F_CPU1_SA_DQ<10>")
		)
		(pad "164" smd rect
			(at 2.050034 -47.174912 270)
			(size 0.519938 1.4986)
			(layers "F.Cu" "F.Mask" "F.Paste")
			(net "GND")
		)
		(pad "165" smd rect
			(at 2.050034 -46.325028 270)
			(size 0.519938 1.4986)
			(layers "F.Cu" "F.Mask" "F.Paste")
			(net "M_F_CPU1_SA_DQ<11>")
		)
		(pad "166" smd rect
			(at 2.050034 -45.47489 270)
			(size 0.519938 1.4986)
			(layers "F.Cu" "F.Mask" "F.Paste")
			(net "GND")
		)
		(pad "167" smd rect
			(at 2.050034 -44.625006 270)
			(size 0.519938 1.4986)
			(layers "F.Cu" "F.Mask" "F.Paste")
			(net "M_F_CPU1_SA_DQS_DN<6>")
		)
		(pad "168" smd rect
			(at 2.050034 -43.775122 270)
			(size 0.519938 1.4986)
			(layers "F.Cu" "F.Mask" "F.Paste")
			(net "M_F_CPU1_SA_DQS_DP<6>")
		)
		(pad "169" smd rect
			(at 2.050034 -42.924984 270)
			(size 0.519938 1.4986)
			(layers "F.Cu" "F.Mask" "F.Paste")
			(net "GND")
		)
		(pad "170" smd rect
			(at 2.050034 -42.0751 270)
			(size 0.519938 1.4986)
			(layers "F.Cu" "F.Mask" "F.Paste")
			(net "M_F_CPU1_SA_DQ<14>")
		)
		(pad "171" smd rect
			(at 2.050034 -41.224962 270)
			(size 0.519938 1.4986)
			(layers "F.Cu" "F.Mask" "F.Paste")
			(net "GND")
		)
		(pad "172" smd rect
			(at 2.050034 -40.375078 270)
			(size 0.519938 1.4986)
			(layers "F.Cu" "F.Mask" "F.Paste")
			(net "M_F_CPU1_SA_DQ<15>")
		)
		(pad "173" smd rect
			(at 2.050034 -39.52494 270)
			(size 0.519938 1.4986)
			(layers "F.Cu" "F.Mask" "F.Paste")
			(net "GND")
		)
		(pad "174" smd rect
			(at 2.050034 -38.675056 270)
			(size 0.519938 1.4986)
			(layers "F.Cu" "F.Mask" "F.Paste")
			(net "M_F_CPU1_SA_DQ<18>")
		)
		(pad "175" smd rect
			(at 2.050034 -37.824918 270)
			(size 0.519938 1.4986)
			(layers "F.Cu" "F.Mask" "F.Paste")
			(net "GND")
		)
		(pad "176" smd rect
			(at 2.050034 -36.975034 270)
			(size 0.519938 1.4986)
			(layers "F.Cu" "F.Mask" "F.Paste")
			(net "M_F_CPU1_SA_DQ<19>")
		)
		(pad "177" smd rect
			(at 2.050034 -36.124896 270)
			(size 0.519938 1.4986)
			(layers "F.Cu" "F.Mask" "F.Paste")
			(net "GND")
		)
		(pad "178" smd rect
			(at 2.050034 -35.275012 270)
			(size 0.519938 1.4986)
			(layers "F.Cu" "F.Mask" "F.Paste")
			(net "M_F_CPU1_SA_DQS_DN<7>")
		)
		(pad "179" smd rect
			(at 2.050034 -34.425128 270)
			(size 0.519938 1.4986)
			(layers "F.Cu" "F.Mask" "F.Paste")
			(net "M_F_CPU1_SA_DQS_DP<7>")
		)
		(pad "180" smd rect
			(at 2.050034 -33.57499 270)
			(size 0.519938 1.4986)
			(layers "F.Cu" "F.Mask" "F.Paste")
			(net "GND")
		)
		(pad "181" smd rect
			(at 2.050034 -32.725106 270)
			(size 0.519938 1.4986)
			(layers "F.Cu" "F.Mask" "F.Paste")
			(net "M_F_CPU1_SA_DQ<22>")
		)
		(pad "182" smd rect
			(at 2.050034 -31.874968 270)
			(size 0.519938 1.4986)
			(layers "F.Cu" "F.Mask" "F.Paste")
			(net "GND")
		)
	)
)
